FILE_TYPE = MULTI_PHYS_TABLE;

PART 'Q_CRYSTAL'

{========================================================================================}
:VALUE         | PACK_TYPE | MATERIAL | PART_NUMBER        = STANDARD        | LIFECYCLE      | PART_NUMBER       | JEDEC_TYPE                        | CLASS | DESCRIPTION                                | COMPONENT_TYPE | LEAD_LENGTH | DAY         ;
{========================================================================================}
 '30MHz'       | 'SM'      | 'IC'     | 'TMP_QBG630000103'(!) = 'End of Design' | 'End of Life'  | 'BG630000103'     |'X_6X_EOL'| 'IC'  | 'XTAL SMD 30MHZ(+-30PPM,16PF)6X30000010'   | 'SMTOTHER'     | ''          | ''         
 '30MHz'       | 'SM'      | 'EMPTY'  | 'TMP_QBG630000103'(!) = 'End of Design' | 'End of Life'  | 'BG630000103'     |'X_6X_EOL'| 'IO'  | 'XTAL SMD 30MHZ(+-30PPM,16PF)6X30000010'   | 'SMTOTHER'     | ''          | ''         
 '24.576MHZ'   | 'SM'      | 'IC'     | 'TMP_QBG624576465'(!) = ''              | 'End of Life'  | 'BG624576465'     |'X_6X_EOL'| 'IC'  | 'XTAL SMD 24.576MHZ(+-30PPM)6X24500072'    | 'SMTOTHER'     | ''          | ''         
 '24.576MHZ'   | 'SM'      | 'EMPTY'  | 'TMP_QBG624576465'(!) = ''              | 'End of Life'  | 'BG624576465'     |'X_6X_EOL'| 'IO'  | 'XTAL SMD 24.576MHZ(+-30PPM)6X24500072'    | 'SMTOTHER'     | ''          | ''         
 '18.432MHZ'   | 'SM'      | 'IC'     | 'TMP_QBG618432601'(!) = ''              | ''             | 'BG618432601'     |'X_F8_H67'| 'IC'  | 'XTAL SMD 18.432 MHZ(+-30PPM,F81840002)'   | 'SMTOTHER'     | ''          | ''         
 '18.432MHZ'   | 'SM'      | 'EMPTY'  | 'TMP_QBG618432601'(!) = ''              | ''             | 'BG618432601'     |'X_F8_H67'| 'IO'  | 'XTAL SMD 18.432 MHZ(+-30PPM,F81840002)'   | 'SMTOTHER'     | ''          | ''         
 '14.318MHZ'   | 'SM'      | 'IC'     | 'QN-BG614318Q25'(!) = 'End of Design' | 'End of Life'  | 'BG614318Q25'     |'X_6XXA_EOL'| 'IC'  | 'XTAL SMD 14.318MHZ(+-20PPM,20PF)'         | 'SMTOTHER'     | ''          | ''         
 '14.318MHZ'   | 'SM'      | 'EMPTY'  | 'QN-BG614318Q25'(!) = 'End of Design' | 'End of Life'  | 'BG614318Q25'     |'X_6XXA_EOL'| 'IO'  | 'XTAL SMD 14.318MHZ(+-20PPM,20PF)'         | 'SMTOTHER'     | ''          | ''         
 '25MHZ'       | 'SM'      | 'IC'     | 'QN-BG625000435'(!) = ''              | 'End of Life'  | 'BG625000435'     |'X_HC49A_EOL'| 'IC'  | 'CRYSTAL SMD 25MHZ(+-30PPM,9C25000355)'    | 'SMTOTHER'     | ''          | ''         
 '25MHZ'       | 'SM'      | 'EMPTY'  | 'QN-BG625000435'(!) = ''              | 'End of Life'  | 'BG625000435'     |'X_HC49A_EOL'| 'IO'  | 'CRYSTAL SMD 25MHZ(+-30PPM,9C25000355)'    | 'SMTOTHER'     | ''          | ''         
 '14.31818MHz' | 'SM'      | 'IC'     | 'BG614318S11'(!)   = ''              | 'End of Life'  | 'BG614318S11'     |'X_HC49A_EOL'| 'IC'  | 'XTAL SMD 14.318MHZ(+-30PPM,9C14300040)LF' | 'SMTOTHER'     | ''          | '20100714' 
 '14.31818MHz' | 'SM'      | 'EMPTY'  | 'BG614318S11'(!)   = ''              | 'End of Life'  | 'BG614318S11'     |'X_HC49A_EOL'| 'IO'  | 'XTAL SMD 14.318MHZ(+-30PPM,9C14300040)LF' | 'SMTOTHER'     | ''          | '20100714' 
 '50MHZ'       | 'SM'      | 'IC'     | 'BG650000003'(!)   = ''              | 'End of Life'  | 'BG650000003'     |'X_7A_EOL'| 'IC'  | 'XTAL SMD 50MHZ(+-15PPM,16PF)7A50020001'   | 'SMTOTHER'     | ''          | '20110211' 
 '50MHZ'       | 'SM'      | 'EMPTY'  | 'BG650000003'(!)   = ''              | 'End of Life'  | 'BG650000003'     |'X_7A_EOL'| 'IO'  | 'XTAL SMD 50MHZ(+-15PPM,16PF)7A50020001'   | 'SMTOTHER'     | ''          | '20110211' 
 '48MHZ'       | 'SMLF'    | 'IC'     | 'BG648000010'(!)   = 'End of Design' | 'End of Life'  | 'BG648000010'     |'X_7A_EOL'| 'IC'  | 'XTAL SMD 48MHZ(+-20PPM,12PF)7A48000065'   | 'SMTOTHER'     | ''          | '2011/3/24'
 '48MHZ'       | 'SMLF'    | 'EMPTY'  | 'BG648000010'(!)   = 'End of Design' | 'End of Life'  | 'BG648000010'     |'X_7A_EOL'| 'IO'  | 'XTAL SMD 48MHZ(+-20PPM,12PF)7A48000065'   | 'SMTOTHER'     | ''          | '2011/3/24'
 '6MHz'        | 'SMLF'    | 'IC'     | 'BG560000001'(!)   = ''              | 'End of Life'  | 'BG560000001'     |'X_HC49A_EOL'| 'IC'  | 'CRYSTAL SMD 6MHZ(20PF+-30PPM0)9C06000077' | 'SMTOTHER'     | ''          | '20111209' 
 '6MHz'        | 'SMLF'    | 'EMPTY'  | 'BG560000001'(!)   = ''              | 'End of Life'  | 'BG560000001'     |'X_HC49A_EOL'| 'IO'  | 'CRYSTAL SMD 6MHZ(20PF+-30PPM0)9C06000077' | 'SMTOTHER'     | ''          | '20111209' 
 '12MHz'       | 'SMLF'    | 'IC'     | 'BG612000009'(!)   = 'End of Design' | 'End of Life'  | 'BG612000009'     |'X_HC49XA_EOL'| 'IC'  | 'XTAL 12MHZ(30PPM.20PF)ESB12.0000F20E35F'  | 'SMTOTHER'     | ''          | '20111209' 
 '12MHz'       | 'SMLF'    | 'EMPTY'  | 'BG612000009'(!)   = 'End of Design' | 'End of Life'  | 'BG612000009'     |'X_HC49XA_EOL'| 'IO'  | 'XTAL 12MHZ(30PPM.20PF)ESB12.0000F20E35F'  | 'SMTOTHER'     | ''          | '20111209' 
 '12MHz'       | 'SMLF'    | 'IC'     | 'BG612000334'(!)   = 'End of Design' | 'End of Life'  | 'BG612000334'     |'X_7A_EOL'| 'IC'  | 'XTAL SMD 12MHZ(+-30PPM,16PF)7A12000017'   | 'SMTOTHER'     | ''          | '20120109' 
 '12MHz'       | 'SMLF'    | 'EMPTY'  | 'BG612000334'(!)   = 'End of Design' | 'End of Life'  | 'BG612000334'     |'X_7A_EOL'| 'IO'  | 'XTAL SMD 12MHZ(+-30PPM,16PF)7A12000017'   | 'SMTOTHER'     | ''          | '20120109' 
 '32.768KHZ'   | 'SMLF'    | 'IC'     | 'BG332768066'(!)   = ''              | ''             | 'BG332768066'     |'X_2S_XTL721'| 'IC'  | 'XTAL SMD 32.768KHZ(20PPM,12.5PF)XTL721'   | 'SMTOTHER'     | ''          | '20120525' 
 '32.768KHZ'   | 'SMLF'    | 'EMPTY'  | 'BG332768066'(!)   = ''              | ''             | 'BG332768066'     |'X_2S_XTL721'| 'IO'  | 'XTAL SMD 32.768KHZ(20PPM,12.5PF)XTL721'   | 'SMTOTHER'     | ''          | '20120525' 
 '32.768KHZ'   | 'SMLF'    | 'IC'     | 'BG332768453'(!)   = ''              | ''             | 'BG332768453'     |'X_2S_FC145'| 'IC'  | 'CRYSTAL SMD 32.768KHZ(+-20PPM,12.5PF)'    | 'SMTOTHER'     | ''          | '20120712' 
 '32.768KHZ'   | 'SMLF'    | 'EMPTY'  | 'BG332768453'(!)   = ''              | ''             | 'BG332768453'     |'X_2S_FC145'| 'IO'  | 'CRYSTAL SMD 32.768KHZ(+-20PPM,12.5PF)'    | 'SMTOTHER'     | ''          | '20120712' 
 '32.768KHZ'   | 'SMLF'    | 'IC'     | 'BG332768077'(!)   = 'End of Design' | 'Comp-Approve' | 'BG332768077'     |'X_2S_XTL721'| 'IC'  | 'CRYSTAL SMD 32.768KHZ(+-20PPM,12.5PF)'    | 'SMTOTHER'     | ''          | '20120917' 
 '32.768KHZ'   | 'SMLF'    | 'EMPTY'  | 'BG332768077'(!)   = 'End of Design' | 'Comp-Approve' | 'BG332768077'     |'X_2S_XTL721'| 'IO'  | 'CRYSTAL SMD 32.768KHZ(+-20PPM,12.5PF)'    | 'SMTOTHER'     | ''          | '20120917' 
 '32.768KHZ'   | 'SMLF'    | 'IC'     | 'BG332768111'(!)   = ''               | ''               | 'BG332768111'     |'X_2S_XTL721'| 'IC'  | 'CRYSTAL SMD 32.768KHZ(+-20PPM,12.5PF)'    | 'SMTOTHER'     | ''          | '20121218' 
 '32.768KHZ'   | 'SMLF'    | 'EMPTY'  | 'BG332768111'(!)   = ''               | ''               | 'BG332768111'     |'X_2S_XTL721'| 'IO'  | 'CRYSTAL SMD 32.768KHZ(+-20PPM,12.5PF)'    | 'SMTOTHER'     | ''          | '20121218' 
 '32.768KHZ'   | 'SMLF'    | 'IC'     | 'BG332768124'(!)   = ''              | ''             | 'BG332768124'     |'X_2S_XTL721'| 'IC'  | 'CRYSTAL SMD 32.768KHZ(+-20PPM,12.5PF)'    | 'SMTOTHER'     | ''          | '20130924' 
 '32.768KHZ'   | 'SMLF'    | 'EMPTY'  | 'BG332768124'(!)   = ''              | ''             | 'BG332768124'     |'X_2S_XTL721'| 'IO'  | 'CRYSTAL SMD 32.768KHZ(+-20PPM,12.5PF)'    | 'SMTOTHER'     | ''          | '20130924' 
 '25MHZ'       | 'SMLF'    | 'IC'     | 'BG625000082'(!)   = 'End of Design' | 'End of Life'  | 'BG625000082'     |'X_HC49_EOL'| 'IC'  | 'XTAL SMD 25MHZ(20PPM,18PF)'               | 'SMTOTHER'     | ''          | '20140226' 
 '25MHZ'       | 'SMLF'    | 'EMPTY'  | 'BG625000082'(!)   = 'End of Design' | 'End of Life'  | 'BG625000082'     |'X_HC49_EOL'| 'IO'  | 'XTAL SMD 25MHZ(20PPM,18PF)'               | 'SMTOTHER'     | ''          | '20140226' 
 '32.768KHZ'   | 'SMLF'    | 'IC'     | 'BG632768012'(!)   = 'End of Design' | 'Comp-Approve' | 'BG632768012'     |'X_2S_XTL721'| 'IC'  | 'CRYSTAL SMD 32.768KHZ(+-20PPM,12.5PF)'    | 'SMTOTHER'     | ''          | '20141103' 
 '32.768KHZ'   | 'SMLF'    | 'EMPTY'  | 'BG632768012'(!)   = 'End of Design' | 'Comp-Approve' | 'BG632768012'     |'X_2S_XTL721'| 'IO'  | 'CRYSTAL SMD 32.768KHZ(+-20PPM,12.5PF)'    | 'SMTOTHER'     | ''          | '20141103' 
 '32.768KHZ'   | 'SMLF'    | 'IC'     | 'BG332768232'(!)   = ''              | ''             | 'BG332768232'     |'X_2S_1TJE125DP1A000M_4-1X1-5'| 'IC'  | 'XTAL 32.768KHZ(20PPM)1TJE125DP1A000M'     | 'SMTOTHER'     | ''          | '20141205' 
 '32.768KHZ'   | 'SMLF'    | 'EMPTY'  | 'BG332768232'(!)   = ''              | ''             | 'BG332768232'     |'X_2S_1TJE125DP1A000M_4-1X1-5'| 'IO'  | 'XTAL 32.768KHZ(20PPM)1TJE125DP1A000M'     | 'SMTOTHER'     | ''          | '20141205' 
 '32.768KHZ'   | 'SMLF'    | 'IC'     | 'BG332768146'(!)   = 'End of Design' | 'P/N Release'  | 'BG332768146'     |'X_2S_XTL721'| 'IC'  | 'XTAL SMD 32.768KHZ(20PPM,12.5PF)AEC'      | 'SMTOTHER'     | ''          | '20160426' 
 '32.768KHZ'   | 'SMLF'    | 'EMPTY'  | 'BG332768146'(!)   = 'End of Design' | 'P/N Release'  | 'BG332768146'     |'X_2S_XTL721'| 'IO'  | 'XTAL SMD 32.768KHZ(20PPM,12.5PF)AEC'      | 'SMTOTHER'     | ''          | '20160426' 
 '32.768KHZ'   | 'SMLF'    | 'IC'     | 'BG332768149'(!)   = ''              | ''             | 'BG332768149'     |'X_2S_AH03200013_3-2X1-5'| 'IC'  | 'XTAL SMD 32.768KHZ(12.5PF,20PPM)AEC'      | 'SMTOTHER'     | ''          | '20160516' 
 '32.768KHZ'   | 'SMLF'    | 'EMPTY'  | 'BG332768149'(!)   = ''              | ''             | 'BG332768149'     |'X_2S_AH03200013_3-2X1-5'| 'IO'  | 'XTAL SMD 32.768KHZ(12.5PF,20PPM)AEC'      | 'SMTOTHER'     | ''          | '20160516' 
 '32.768KHZ'   | 'SMLF'    | 'IC'     | 'BG3327680C7'(!)   = 'End of Design' | 'End of Life'  | 'BG3327680C7'     |'X_2S_ETST00327000JE_3-2X1-5_EOL'| 'IC'  | 'CRYSTAL SMD 32.768KHZ(+-20PPM,12.5PF)'    | 'SMTOTHER'     | ''          | '20160808' 
 '32.768KHZ'   | 'SMLF'    | 'EMPTY'  | 'BG3327680C7'(!)   = 'End of Design' | 'End of Life'  | 'BG3327680C7'     |'X_2S_ETST00327000JE_3-2X1-5_EOL'| 'IO'  | 'CRYSTAL SMD 32.768KHZ(+-20PPM,12.5PF)'    | 'SMTOTHER'     | ''          | '20160808' 
 '32.768KHZ'   | 'SMLF'    | 'IC'     | 'BG332768152'(!)   = 'End of Design' | 'Comp-Approve' | 'BG332768152'     |'X_2S_AH03200013_3-2X1-5'| 'IC'  | 'XTAL SMD 32.768KHZ(20PPM,7PF)AH03200001'  | 'SMTOTHER'     | ''          | '20160816' 
 '32.768KHZ'   | 'SMLF'    | 'EMPTY'  | 'BG332768152'(!)   = 'End of Design' | 'Comp-Approve' | 'BG332768152'     |'X_2S_AH03200013_3-2X1-5'| 'IO'  | 'XTAL SMD 32.768KHZ(20PPM,7PF)AH03200001'  | 'SMTOTHER'     | ''          | '20160816' 
 '32.768KHZ'   | 'SMLF'    | 'IC'     | 'BG3327680C4'(!)   = 'End of Design' | 'End of Life'  | 'BG3327680C4'     |'X_2S_ETST00327000JE_3-2X1-5_EOL'| 'IC'  | 'CRYSTAL SMD 32.768KHZ(+-20PPM,12.5PF)'    | 'SMTOTHER'     | ''          | '20160923' 
 '32.768KHZ'   | 'SMLF'    | 'EMPTY'  | 'BG3327680C4'(!)   = 'End of Design' | 'End of Life'  | 'BG3327680C4'     |'X_2S_ETST00327000JE_3-2X1-5_EOL'| 'IO'  | 'CRYSTAL SMD 32.768KHZ(+-20PPM,12.5PF)'    | 'SMTOTHER'     | ''          | '20160923' 
 '32.768KHZ'   | 'SMLF'    | 'IC'     | 'BG332768133'(!)   = ''              | ''             | 'BG332768133'     |'X_2S_XTL721'| 'IC'  | 'XTAL 32.768KHZ(10PPM,12.5PF)9H03270039'   | 'SMTOTHER'     | ''          | '20170517' 
 '32.768KHZ'   | 'SMLF'    | 'EMPTY'  | 'BG332768133'(!)   = ''              | ''             | 'BG332768133'     |'X_2S_XTL721'| 'IO'  | 'XTAL 32.768KHZ(10PPM,12.5PF)9H03270039'   | 'SMTOTHER'     | ''          | '20170517' 
 '32.768KHZ'   | 'SMLF'    | 'IC'     | 'BG332768084'(!)   = 'End of Design' | 'Comp-Approve' | 'BG332768084'     |'X_2S_9H03200012_2X1-2'| 'IC'  | 'CRYSTAL SMD 32.768KHZ(+-20PPM,12.5PF)'    | 'SMTOTHER'     | ''          | '20171218' 
 '32.768KHZ'   | 'SMLF'    | 'EMPTY'  | 'BG332768084'(!)   = 'End of Design' | 'Comp-Approve' | 'BG332768084'     |'X_2S_9H03200012_2X1-2'| 'IO'  | 'CRYSTAL SMD 32.768KHZ(+-20PPM,12.5PF)'    | 'SMTOTHER'     | ''          | '20171218' 
 '32.768KHZ'   | 'SMLF'    | 'IC'     | 'BG3327680B4'(!)   = 'End of Design' | 'Comp-Approve' | 'BG3327680B4'     |'X_2S_XTL721'| 'IC'  | 'XTAL 32.768KHZ(+-20PPM,9PF)X1A0001410002' | 'SMTOTHER'     | ''          | '20180402' 
 '32.768KHZ'   | 'SMLF'    | 'EMPTY'  | 'BG3327680B4'(!)   = 'End of Design' | 'Comp-Approve' | 'BG3327680B4'     |'X_2S_XTL721'| 'IO'  | 'XTAL 32.768KHZ(+-20PPM,9PF)X1A0001410002' | 'SMTOTHER'     | ''          | '20180402' 
 '32.768KHZ'   | 'SMLF'    | 'IC'     | 'BG332768144'(!)   = 'End of Design' | 'Comp-Approve' | 'BG332768144'     |'X_2S_XTL721'| 'IC'  | 'XTAL32.768KHZ(10PPM,12.5PF)9H03200051'    | 'SMTOTHER'     | ''          | '20191017' 
 '32.768KHZ'   | 'SMLF'    | 'EMPTY'  | 'BG332768144'(!)   = 'End of Design' | 'Comp-Approve' | 'BG332768144'     |'X_2S_XTL721'| 'IO'  | 'XTAL32.768KHZ(10PPM,12.5PF)9H03200051'    | 'SMTOTHER'     | ''          | '20191017' 
 '12MHZ'       | 'SMLF'    | 'IC'     | 'BG612000004'(!)   = ''              | 'End of Life'  | 'BG612000004'     |'X_HC49A_EOL'| 'IC'  | 'XTAL 12MHZ(+-30PPM)9C12000065'            | 'SMTOTHER'     | ''          | '20191030' 
 '12MHZ'       | 'SMLF'    | 'EMPTY'  | 'BG612000004'(!)   = ''              | 'End of Life'  | 'BG612000004'     |'X_HC49A_EOL'| 'IO'  | 'XTAL 12MHZ(+-30PPM)9C12000065'            | 'SMTOTHER'     | ''          | '20191030' 
 '32.768KHZ'   | 'SMLF'    | 'IC'     | 'BG332768142'(!)   = ''              | ''             | 'BG332768142'     |'X_2S_XTL721'| 'IC'  | 'XTAL 32.768KHZ(10PPM,12.5PF)X1A000141000' | 'SMTOTHER'     | ''          | '20200225' 
 '32.768KHZ'   | 'SMLF'    | 'EMPTY'  | 'BG332768142'(!)   = ''              | ''             | 'BG332768142'     |'X_2S_XTL721'| 'IO'  | 'XTAL 32.768KHZ(10PPM,12.5PF)X1A000141000' | 'SMTOTHER'     | ''          | '20200225' 
 '32.768KHZ'   | 'SMLF'    | 'IC'     | 'BG332768132'(!)   = ''              | ''             | 'BG332768132'     |'X_2S_AH03200013_3-2X1-5_H36'| 'IC'  | 'XTAL SMD 32.768KHZ 12.5PF EXS00A-MU00503' | 'SMTOTHER'     | ''          | '20200714' 
 '32.768KHZ'   | 'SMLF'    | 'EMPTY'  | 'BG332768132'(!)   = ''              | ''             | 'BG332768132'     |'X_2S_AH03200013_3-2X1-5_H36'| 'IO'  | 'XTAL SMD 32.768KHZ 12.5PF EXS00A-MU00503' | 'SMTOTHER'     | ''          | '20200714' 
 '8MHZ'        | 'SMLF'    | 'IC'     | 'BG580000027'(!)   = ''              | ''             | 'BG580000027'     |'X_2S_STD-CSK-3_5X3-2'| 'IC'  | 'XTAL 8MHZ(8PF,+-20PPM)  STD-CSK-3'        | 'SMTOTHER'     | ''          | '20210316' 
 '8MHZ'        | 'SMLF'    | 'EMPTY'  | 'BG580000027'(!)   = ''              | ''             | 'BG580000027'     |'X_2S_STD-CSK-3_5X3-2'| 'IO'  | 'XTAL 8MHZ(8PF,+-20PPM)  STD-CSK-3'        | 'SMTOTHER'     | ''          | '20210316' 
 '12MHZ'       | 'SMLF'    | 'IC'     | 'BG6120000D0'(!)   = ''              | ''             | 'BG6120000D0'     |'X_2S_GC1200037_11-7X4-8'| 'IC'  | 'XTAL SMD 12MHZ(+-30PPM, 20PF)GC1200037'   | 'SMTOTHER'     | ''          | '20211018' 
 '12MHZ'       | 'SMLF'    | 'EMPTY'  | 'BG6120000D0'(!)   = ''              | ''             | 'BG6120000D0'     |'X_2S_GC1200037_11-7X4-8'| 'IO'  | 'XTAL SMD 12MHZ(+-30PPM, 20PF)GC1200037'   | 'SMTOTHER'     | ''          | '20211018' 
 '32.768KHZ'   | 'SMLF'    | 'IC'     | 'BG632768012SEL1'(!) = ''              | ''             | 'BG632768012SEL1' |'X_2S_XTL721'| 'IC'  | 'XTAL SMD 32.768KHZ(20PPM,12.5PF) SELASN'  | 'SMTOTHER'     | ''          | '20230629' 
 '32.768KHZ'   | 'SMLF'    | 'EMPTY'  | 'BG632768012SEL1'(!) = ''              | ''             | 'BG632768012SEL1' |'X_2S_XTL721'| 'IO'  | 'XTAL SMD 32.768KHZ(20PPM,12.5PF) SELASN'  | 'SMTOTHER'     | ''          | '20230629' 
 '32.768KHZ'   | 'SMLF'    | 'IC'     | 'BG332768124SEL1'(!) = ''              | ''             | 'BG332768124SEL1' |'X_2S_XTL721'| 'IC'  | 'XTAL SMD 32.768KHZ(20PPM,12.5PF)SELASN'   | 'SMTOTHER'     | ''          | '20230713' 
 '32.768KHZ'   | 'SMLF'    | 'EMPTY'  | 'BG332768124SEL1'(!) = ''              | ''             | 'BG332768124SEL1' |'X_2S_XTL721'| 'IO'  | 'XTAL SMD 32.768KHZ(20PPM,12.5PF)SELASN'   | 'SMTOTHER'     | ''          | '20230713' 

END_PART

END.

